# T6G (Grand Teton) — schematic netlist excerpt (pin names and nets, part order shuffled) for the footprints in the layout excerpt that follows; sources: Cadence DE-HDL packaged netlist, KiCad conversion of 04192023_DAF0TMB3IC0_F0TG_MB_C_brd_V02_OCP.brd

C730  Q_CAP_DIFFBUS  DIFF BUS_0.22UF 6.3V 20% X6S  pkg C0201  page 66 : \1\ = P5E_CPU1_P1_TX_C_DN<5> ; \2\ = P5E_CPU1_P1_TX_DN<5>
R3493  Q_RES  100K 1% EMPTY  pkg 0402LF  page 129 : A = GPU_FPGA_EROT_RST_BUF_R_N ; B = GND
L19  Q_INDUCTOR  FCM2012KF-601T/0.5A IND  pkg SMLF  page 182 : \1\ = P3V3_AUX ; \2\ = P3V3_9ZXL045_P0

(kicad_pcb
	(version 20260206)
	(generator "pcbnew")
	(generator_version "10.0")
	(general
		(thickness 1.6)
		(legacy_teardrops no)
	)
	(paper "A4")
	(title_block
		(title "04192023_DAF0TMB3IC0_F0TG_MB_C_brd_V02_OCP.brd")
		(comment 1 "Grand Teton / footprints 3449-3452 of 8354")
	)
	(layers
		(0 "F.Cu" signal "TOP")
		(4 "In1.Cu" signal "GND")
		(6 "In2.Cu" signal "IN1")
		(8 "In3.Cu" signal "GND1")
		(10 "In4.Cu" signal "IN2")
		(12 "In5.Cu" signal "GND2")
		(14 "In6.Cu" signal "IN3")
		(16 "In7.Cu" signal "GND3")
		(18 "In8.Cu" signal "VCC")
		(20 "In9.Cu" signal "VCC1")
		(22 "In10.Cu" signal "GND4")
		(24 "In11.Cu" signal "IN4")
		(26 "In12.Cu" signal "GND5")
		(28 "In13.Cu" signal "IN5")
		(30 "In14.Cu" signal "GND6")
		(32 "In15.Cu" signal "IN6")
		(34 "In16.Cu" signal "GND7")
		(2 "B.Cu" signal "BOTTOM")
		(9 "F.Adhes" user "F.Adhesive")
		(11 "B.Adhes" user "B.Adhesive")
		(13 "F.Paste" user "Package Geometry/Pastemask Top")
		(15 "B.Paste" user "Package Geometry/Pastemask Bottom")
		(5 "F.SilkS" user "Ref Des/Silkscreen Top")
		(7 "B.SilkS" user "Ref Des/Silkscreen Bottom")
		(1 "F.Mask" user "Board Geometry/Soldermask Top")
		(3 "B.Mask" user "Board Geometry/Soldermask Bottom")
		(17 "Dwgs.User" user "User.Drawings")
		(19 "Cmts.User" user "User.Comments")
		(21 "Eco1.User" user "User.Eco1")
		(23 "Eco2.User" user "User.Eco2")
		(25 "Edge.Cuts" user "Board Geometry/Outline")
		(27 "Margin" user)
		(31 "F.CrtYd" user "Package Geometry/Place Bound Top")
		(29 "B.CrtYd" user "Package Geometry/Place Bound Bottom")
		(35 "F.Fab" user "Ref Des/Assembly Top")
		(33 "B.Fab" user "Ref Des/Assembly Bottom")
	)
	(footprint ""
		(layer "F.Cu")
		(at 103.505 -419.989)
		(property "Reference" "R3493"
			(at 0 0 0)
			(layer "F.SilkS")
			(hide yes)
			(effects
				(font
					(size 1.27 1.27)
				)
			)
		)
		(property "Value" ""
			(at 0 0 0)
			(layer "F.Fab")
			(effects
				(font
					(size 1.27 1.27)
				)
			)
		)
		(duplicate_pad_numbers_are_jumpers no)
		(fp_line
			(start -0.7874 -0.4064)
			(end 0.7874 -0.4064)
			(stroke
				(width 0.1524)
				(type default)
			)
			(layer "F.SilkS")
		)
		(fp_line
			(start -0.7874 0.4064)
			(end -0.7874 -0.4064)
			(stroke
				(width 0.1524)
				(type default)
			)
			(layer "F.SilkS")
		)
		(fp_line
			(start 0.7874 -0.4064)
			(end 0.7874 0.4064)
			(stroke
				(width 0.1524)
				(type default)
			)
			(layer "F.SilkS")
		)
		(fp_line
			(start 0.7874 0.4064)
			(end -0.7874 0.4064)
			(stroke
				(width 0.1524)
				(type default)
			)
			(layer "F.SilkS")
		)
		(fp_line
			(start -0.67945 -0.305054)
			(end -0.12065 -0.305054)
			(stroke
				(width 0.1)
				(type default)
			)
			(layer "F.Fab")
		)
		(fp_line
			(start -0.67945 0.3048)
			(end -0.67945 -0.305054)
			(stroke
				(width 0.1)
				(type default)
			)
			(layer "F.Fab")
		)
		(fp_line
			(start -0.12065 -0.305054)
			(end -0.12065 -0.2794)
			(stroke
				(width 0.1)
				(type default)
			)
			(layer "F.Fab")
		)
		(fp_line
			(start -0.12065 -0.2794)
			(end 0.12065 -0.2794)
			(stroke
				(width 0.1)
				(type default)
			)
			(layer "F.Fab")
		)
		(fp_line
			(start -0.12065 0.2794)
			(end -0.12065 0.3048)
			(stroke
				(width 0.1)
				(type default)
			)
			(layer "F.Fab")
		)
		(fp_line
			(start -0.12065 0.3048)
			(end -0.67945 0.3048)
			(stroke
				(width 0.1)
				(type default)
			)
			(layer "F.Fab")
		)
		(fp_line
			(start 0.120396 0.2794)
			(end -0.12065 0.2794)
			(stroke
				(width 0.1)
				(type default)
			)
			(layer "F.Fab")
		)
		(fp_line
			(start 0.120396 0.3048)
			(end 0.120396 0.2794)
			(stroke
				(width 0.1)
				(type default)
			)
			(layer "F.Fab")
		)
		(fp_line
			(start 0.12065 -0.3048)
			(end 0.67945 -0.3048)
			(stroke
				(width 0.1)
				(type default)
			)
			(layer "F.Fab")
		)
		(fp_line
			(start 0.12065 -0.2794)
			(end 0.12065 -0.3048)
			(stroke
				(width 0.1)
				(type default)
			)
			(layer "F.Fab")
		)
		(fp_line
			(start 0.67945 -0.3048)
			(end 0.67945 0.3048)
			(stroke
				(width 0.1)
				(type default)
			)
			(layer "F.Fab")
		)
		(fp_line
			(start 0.67945 0.3048)
			(end 0.120396 0.3048)
			(stroke
				(width 0.1)
				(type default)
			)
			(layer "F.Fab")
		)
		(pad "1" smd circle
			(at -0.40005 0)
			(size 0 0)
			(layers "F.Cu" "F.Mask" "F.Paste")
			(net "GPU_FPGA_EROT_RST_BUF_R_N")
		)
		(pad "2" smd circle
			(at 0.40005 0)
			(size 0 0)
			(layers "F.Cu" "F.Mask" "F.Paste")
			(net "GND")
		)
	)
	(footprint ""
		(layer "F.Cu")
		(at 83.239102 -373.03583 -90)
		(property "Reference" "C730"
			(at 0 0 270)
			(layer "F.SilkS")
			(hide yes)
			(effects
				(font
					(size 1.27 1.27)
				)
			)
		)
		(property "Value" ""
			(at 0 0 270)
			(layer "F.Fab")
			(effects
				(font
					(size 1.27 1.27)
				)
			)
		)
		(duplicate_pad_numbers_are_jumpers no)
		(fp_line
			(start -0.299974 0.150114)
			(end -0.299974 -0.150114)
			(stroke
				(width 0.1)
				(type default)
			)
			(layer "F.Fab")
		)
		(fp_line
			(start 0.299974 0.150114)
			(end -0.299974 0.150114)
			(stroke
				(width 0.1)
				(type default)
			)
			(layer "F.Fab")
		)
		(fp_line
			(start -0.299974 -0.150114)
			(end 0.299974 -0.150114)
			(stroke
				(width 0.1)
				(type default)
			)
			(layer "F.Fab")
		)
		(fp_line
			(start 0.299974 -0.150114)
			(end 0.299974 0.150114)
			(stroke
				(width 0.1)
				(type default)
			)
			(layer "F.Fab")
		)
		(pad "1" smd rect
			(at -0.2667 0 270)
			(size 0.3048 0.381)
			(layers "F.Cu" "F.Mask" "F.Paste")
			(net "P5E_CPU1_P1_TX_C_DN<5>")
		)
		(pad "2" smd rect
			(at 0.2667 0 270)
			(size 0.3048 0.381)
			(layers "F.Cu" "F.Mask" "F.Paste")
			(net "P5E_CPU1_P1_TX_DN<5>")
		)
	)
	(footprint ""
		(layer "F.Cu")
		(at 281.94 -430.022 -90)
		(property "Reference" "L19"
			(at 0 0 270)
			(layer "F.SilkS")
			(hide yes)
			(effects
				(font
					(size 1.27 1.27)
				)
			)
		)
		(property "Value" ""
			(at 0 0 270)
			(layer "F.Fab")
			(effects
				(font
					(size 1.27 1.27)
				)
			)
		)
		(duplicate_pad_numbers_are_jumpers no)
		(fp_line
			(start 1.63576 0.8128)
			(end -1.63576 0.8128)
			(stroke
				(width 0.1524)
				(type default)
			)
			(layer "F.SilkS")
		)
		(fp_line
			(start -1.63576 -0.8128)
			(end -1.63576 0.8128)
			(stroke
				(width 0.1524)
				(type default)
			)
			(layer "F.SilkS")
		)
		(fp_line
			(start -1.63576 -0.8128)
			(end 1.63576 -0.8128)
			(stroke
				(width 0.1524)
				(type default)
			)
			(layer "F.SilkS")
		)
		(fp_line
			(start 1.63576 -0.8128)
			(end 1.63576 0.8128)
			(stroke
				(width 0.1524)
				(type default)
			)
			(layer "F.SilkS")
		)
		(fp_line
			(start -1.56083 0.7366)
			(end -1.524 0.7366)
			(stroke
				(width 0.1)
				(type default)
			)
			(layer "F.Fab")
		)
		(fp_line
			(start -1.524 0.7366)
			(end 1.524 0.7366)
			(stroke
				(width 0.1)
				(type default)
			)
			(layer "F.Fab")
		)
		(fp_line
			(start 1.524 0.7366)
			(end 1.560576 0.7366)
			(stroke
				(width 0.1)
				(type default)
			)
			(layer "F.Fab")
		)
		(fp_line
			(start 1.560576 0.7366)
			(end 1.560576 -0.738632)
			(stroke
				(width 0.1)
				(type default)
			)
			(layer "F.Fab")
		)
		(fp_line
			(start -1.56083 -0.738632)
			(end -1.56083 0.7366)
			(stroke
				(width 0.1)
				(type default)
			)
			(layer "F.Fab")
		)
		(fp_line
			(start 1.560576 -0.738632)
			(end -1.56083 -0.738632)
			(stroke
				(width 0.1)
				(type default)
			)
			(layer "F.Fab")
		)
		(pad "1" smd rect
			(at -0.94996 0 90)
			(size 1.1176 1.3716)
			(layers "F.Cu" "F.Mask" "F.Paste")
			(net "P3V3_AUX")
		)
		(pad "2" smd rect
			(at 0.94996 0 90)
			(size 1.1176 1.3716)
			(layers "F.Cu" "F.Mask" "F.Paste")
			(net "P3V3_9ZXL045_P0")
		)
	)
	(footprint ""
		(layer "F.Cu")
		(at 198.926196 -412.947612)
		(property "Reference" "ME4"
			(at 0 0 0)
			(layer "F.SilkS")
			(hide yes)
			(effects
				(font
					(size 1.27 1.27)
				)
			)
		)
		(property "Value" ""
			(at 0 0 0)
			(layer "F.Fab")
			(effects
				(font
					(size 1.27 1.27)
				)
			)
		)
		(duplicate_pad_numbers_are_jumpers no)
		(fp_line
			(start 0 -5.999988)
			(end 0 -4.475988)
			(stroke
				(width 0.1524)
				(type default)
			)
			(layer "F.SilkS")
		)
		(fp_line
			(start 0 -1.524)
			(end 0 0)
			(stroke
				(width 0.1524)
				(type default)
			)
			(layer "F.SilkS")
		)
		(fp_line
			(start 0 0)
			(end 1.524 0)
			(stroke
				(width 0.1524)
				(type default)
			)
			(layer "F.SilkS")
		)
		(fp_line
			(start 1.524 -5.999988)
			(end 0 -5.999988)
			(stroke
				(width 0.1524)
				(type default)
			)
			(layer "F.SilkS")
		)
		(fp_line
			(start 25.475946 -5.999988)
			(end 26.999946 -5.999988)
			(stroke
				(width 0.1524)
				(type default)
			)
			(layer "F.SilkS")
		)
		(fp_line
			(start 26.999946 -5.999988)
			(end 26.999946 -4.475988)
			(stroke
				(width 0.1524)
				(type default)
			)
			(layer "F.SilkS")
		)
		(fp_line
			(start 26.999946 -1.524)
			(end 26.999946 0)
			(stroke
				(width 0.1524)
				(type default)
			)
			(layer "F.SilkS")
		)
		(fp_line
			(start 26.999946 0)
			(end 25.475946 0)
			(stroke
				(width 0.1524)
				(type default)
			)
			(layer "F.SilkS")
		)
		(fp_text user "S/N"
			(at 0.2032 -4.59105 0)
			(unlocked yes)
			(layer "F.SilkS")
			(effects
				(font
					(size 1.905 1.4224)
					(thickness 0.1524)
				)
				(justify left)
			)
		)
	)
)
